(kicad_pcb
	(version 20240108)
	(generator "pcbnew")
	(generator_version "8.0")
	(general
		(thickness 1.62)
		(legacy_teardrops no)
	)
	(paper "A4")
	(title_block
		(title "Jetson Orin Baseboard")
		(date "2025-03-12")
		(rev "1.3.4")
		(company "Antmicro Ltd")
		(comment 1 "www.antmicro.com")
		(comment 9 "footprints 231-232 of 677")
	)
	(layers
		(0 "F.Cu" signal)
		(1 "In1.Cu" signal)
		(2 "In2.Cu" signal)
		(3 "In3.Cu" signal)
		(4 "In4.Cu" jumper)
		(5 "In5.Cu" signal)
		(6 "In6.Cu" signal)
		(31 "B.Cu" signal)
		(32 "B.Adhes" user "B.Adhesive")
		(33 "F.Adhes" user "F.Adhesive")
		(34 "B.Paste" user)
		(35 "F.Paste" user)
		(36 "B.SilkS" user "B.Silkscreen")
		(37 "F.SilkS" user "F.Silkscreen")
		(38 "B.Mask" user)
		(39 "F.Mask" user)
		(40 "Dwgs.User" user "User.Drawings")
		(41 "Cmts.User" user "User.Comments")
		(42 "Eco1.User" user "User.Eco1")
		(43 "Eco2.User" user "User.Eco2")
		(44 "Edge.Cuts" user)
		(45 "Margin" user)
		(46 "B.CrtYd" user "B.Courtyard")
		(47 "F.CrtYd" user "F.Courtyard")
		(48 "B.Fab" user)
		(49 "F.Fab" user)
	)
	(footprint "antmicro-footprints:R_0402_1005Metric"
		(layer "F.Cu")
		(at 68.85 124.8 90)
		(descr "Resistor SMD 0402")
		(tags "resistor SMD 0402")
		(property "Reference" "R106"
			(at 0.825 0.425 90)
			(layer "F.SilkS")
			(effects
				(font
					(size 0.7 0.7)
					(thickness 0.15)
				)
				(justify left bottom)
			)
		)
		(property "Value" "R_4k7_0402"
			(at 0 1.4 90)
			(layer "F.Fab")
			(effects
				(font
					(size 0.7 0.7)
					(thickness 0.15)
				)
				(justify left bottom)
			)
		)
		(property "Footprint" "antmicro-footprints:R_0402_1005Metric"
			(at 0 0 90)
			(layer "F.Fab")
			(hide yes)
			(effects
				(font
					(size 1.27 1.27)
					(thickness 0.15)
				)
			)
		)
		(property "Datasheet" "https://www.bourns.com/docs/product-datasheets/cr.pdf"
			(at 0 0 90)
			(layer "F.Fab")
			(hide yes)
			(effects
				(font
					(size 1.27 1.27)
					(thickness 0.15)
				)
			)
		)
		(property "Author" "Antmicro"
			(at 193.65 55.95 0)
			(layer "F.Fab")
			(hide yes)
			(effects
				(font
					(size 1 1)
					(thickness 0.15)
				)
			)
		)
		(property "License" "Apache-2.0"
			(at 193.65 55.95 0)
			(layer "F.Fab")
			(hide yes)
			(effects
				(font
					(size 1 1)
					(thickness 0.15)
				)
			)
		)
		(property "MPN" "CR0402-FX-4701GLF"
			(at 193.65 55.95 0)
			(layer "F.Fab")
			(hide yes)
			(effects
				(font
					(size 1 1)
					(thickness 0.15)
				)
			)
		)
		(property "Manufacturer" "Bourns"
			(at 193.65 55.95 0)
			(layer "F.Fab")
			(hide yes)
			(effects
				(font
					(size 1 1)
					(thickness 0.15)
				)
			)
		)
		(property "Tolerance" "1%"
			(at 193.65 55.95 0)
			(layer "F.Fab")
			(hide yes)
			(effects
				(font
					(size 1 1)
					(thickness 0.15)
				)
			)
		)
		(property "Val" "4k7"
			(at 193.65 55.95 0)
			(layer "F.Fab")
			(hide yes)
			(effects
				(font
					(size 1 1)
					(thickness 0.15)
				)
			)
		)
		(sheetname "USB Debug, DP")
		(sheetfile "usb.kicad_sch")
		(attr smd)
		(fp_rect
			(start -0.925 -0.47)
			(end 0.925 0.47)
			(stroke
				(width 0.05)
				(type default)
			)
			(fill none)
			(layer "F.CrtYd")
		)
		(fp_rect
			(start -0.5 -0.25)
			(end 0.5 0.25)
			(stroke
				(width 0.15)
				(type solid)
			)
			(fill none)
			(layer "F.Fab")
		)
		(fp_text user "License: Apache-2.0"
			(at -0.95 5.169 90)
			(layer "F.Fab")
			(hide yes)
			(effects
				(font
					(size 0.7 0.7)
					(thickness 0.15)
				)
				(justify left bottom)
			)
		)
		(fp_text user "Author: Antmicro"
			(at -0.95 4.169 90)
			(layer "F.Fab")
			(hide yes)
			(effects
				(font
					(size 0.7 0.7)
					(thickness 0.15)
				)
				(justify left bottom)
			)
		)
		(fp_text user "${REFERENCE}"
			(at -0.95 3.168 90)
			(layer "F.Fab")
			(hide yes)
			(effects
				(font
					(size 0.7 0.7)
					(thickness 0.15)
				)
				(justify left bottom)
			)
		)
		(pad "1" smd roundrect
			(at -0.48 0 90)
			(size 0.59 0.64)
			(layers "F.Cu" "F.Paste" "F.Mask")
			(roundrect_rratio 0.25)
			(net 147 "Net-(D9-A)")
			(pintype "passive")
		)
		(pad "2" smd roundrect
			(at 0.48 0 90)
			(size 0.59 0.64)
			(layers "F.Cu" "F.Paste" "F.Mask")
			(roundrect_rratio 0.25)
			(net 261 "/USB Debug, DP/USBC0_VBUS")
			(pintype "passive")
		)
	)
	(footprint "antmicro-footprints:WQFN-40_1EP_6x3mm_Pitch0.4mm_EP4.7x2.7mm"
		(layer "F.Cu")
		(at 74.75 106.867469 180)
		(property "Reference" "U10"
			(at -1.8 2.317469 0)
			(unlocked yes)
			(layer "F.SilkS")
			(effects
				(font
					(size 0.7 0.7)
					(thickness 0.15)
				)
				(justify left bottom)
			)
		)
		(property "Value" "TUSB1046-DCIRNQ"
			(at 0 3.4 180)
			(unlocked yes)
			(layer "F.Fab")
			(effects
				(font
					(size 0.7 0.7)
					(thickness 0.15)
				)
				(justify left bottom)
			)
		)
		(property "Footprint" "antmicro-footprints:WQFN-40_1EP_6x3mm_Pitch0.4mm_EP4.7x2.7mm"
			(at 0 0 180)
			(layer "F.Fab")
			(hide yes)
			(effects
				(font
					(size 1.27 1.27)
					(thickness 0.15)
				)
			)
		)
		(property "Datasheet" "https://www.ti.com/lit/ds/sllsew2d/sllsew2d.pdf?ts=1662107117482&ref_url=https%253A%252F%252Fwww.google.com%252F"
			(at 0 0 180)
			(layer "F.Fab")
			(hide yes)
			(effects
				(font
					(size 1.27 1.27)
					(thickness 0.15)
				)
			)
		)
		(property "Author" "Antmicro"
			(at 149.5 213.734938 0)
			(layer "F.Fab")
			(hide yes)
			(effects
				(font
					(size 1 1)
					(thickness 0.15)
				)
			)
		)
		(property "License" "Apache-2.0"
			(at 149.5 213.734938 0)
			(layer "F.Fab")
			(hide yes)
			(effects
				(font
					(size 1 1)
					(thickness 0.15)
				)
			)
		)
		(property "MPN" "TUSB1046-DCIRNQT"
			(at 149.5 213.734938 0)
			(layer "F.Fab")
			(hide yes)
			(effects
				(font
					(size 1 1)
					(thickness 0.15)
				)
			)
		)
		(property "Manufacturer" "Texas Instruments"
			(at 149.5 213.734938 0)
			(layer "F.Fab")
			(hide yes)
			(effects
				(font
					(size 1 1)
					(thickness 0.15)
				)
			)
		)
		(sheetname "USB Debug, DP")
		(sheetfile "usb.kicad_sch")
		(attr smd)
		(fp_line
			(start 3.1 2.1)
			(end 2.398 2.1)
			(stroke
				(width 0.15)
				(type solid)
			)
			(layer "F.SilkS")
		)
		(fp_line
			(start 3.1 1.6)
			(end 3.1 2.1)
			(stroke
				(width 0.15)
				(type solid)
			)
			(layer "F.SilkS")
		)
		(fp_line
			(start 3.1 -2.101)
			(end 3.1 -1.601)
			(stroke
				(width 0.15)
				(type solid)
			)
			(layer "F.SilkS")
		)
		(fp_line
			(start 3.1 -2.101)
			(end 2.398 -2.101)
			(stroke
				(width 0.15)
				(type solid)
			)
			(layer "F.SilkS")
		)
		(fp_line
			(start -2.4 2.1)
			(end -3.101 2.1)
			(stroke
				(width 0.15)
				(type solid)
			)
			(layer "F.SilkS")
		)
		(fp_line
			(start -2.4 -2.101)
			(end -3.101 -2.101)
			(stroke
				(width 0.15)
				(type solid)
			)
			(layer "F.SilkS")
		)
		(fp_line
			(start -3.101 2.1)
			(end -3.101 1.6)
			(stroke
				(width 0.15)
				(type solid)
			)
			(layer "F.SilkS")
		)
		(fp_circle
			(center -3.8 -1.41)
			(end -3.75 -1.36)
			(stroke
				(width 0.15)
				(type solid)
			)
			(fill solid)
			(layer "F.SilkS")
		)
		(fp_rect
			(start -3.5 -2.5)
			(end 3.499 2.499)
			(stroke
				(width 0.05)
				(type solid)
			)
			(fill none)
			(layer "F.CrtYd")
		)
		(fp_line
			(start 2.898 1.898)
			(end -2.9 1.898)
			(stroke
				(width 0.15)
				(type solid)
			)
			(layer "F.Fab")
		)
		(fp_line
			(start 2.898 -1.901)
			(end 2.898 1.898)
			(stroke
				(width 0.15)
				(type solid)
			)
			(layer "F.Fab")
		)
		(fp_line
			(start -2.2 -1.9)
			(end 2.898 -1.901)
			(stroke
				(width 0.15)
				(type solid)
			)
			(layer "F.Fab")
		)
		(fp_line
			(start -2.9 1.898)
			(end -2.9 -1.2)
			(stroke
				(width 0.15)
				(type solid)
			)
			(layer "F.Fab")
		)
		(fp_line
			(start -2.9 -1.2)
			(end -2.2 -1.9)
			(stroke
				(width 0.15)
				(type solid)
			)
			(layer "F.Fab")
		)
		(fp_text user "Author: Antmicro"
			(at -3.101 5.099 180)
			(layer "F.Fab")
			(hide yes)
			(effects
				(font
					(size 0.7 0.7)
					(thickness 0.15)
				)
				(justify left bottom)
			)
		)
		(fp_text user "${REFERENCE}"
			(at -3.101 4.099 180)
			(layer "F.Fab")
			(hide yes)
			(effects
				(font
					(size 0.7 0.7)
					(thickness 0.15)
				)
				(justify left bottom)
			)
		)
		(fp_text user "License: Apache-2.0"
			(at -3.101 6.099 180)
			(layer "F.Fab")
			(hide yes)
			(effects
				(font
					(size 0.7 0.7)
					(thickness 0.15)
				)
				(justify left bottom)
			)
		)
		(pad "1" smd roundrect
			(at -2.9 -1.401 270)
			(size 0.2 0.6)
			(layers "F.Cu" "F.Paste" "F.Mask")
			(roundrect_rratio 0.25)
			(net 87 "+3V3")
			(pinfunction "VCC")
			(pintype "power_in")
		)
		(pad "2" smd roundrect
			(at -2.9 -1 270)
			(size 0.2 0.6)
			(layers "F.Cu" "F.Paste" "F.Mask")
			(roundrect_rratio 0.25)
			(net 308 "/USB Debug, DP/USBC0_DPEQ1")
			(pinfunction "DPEQ1")
			(pintype "input")
		)
		(pad "3" smd roundrect
			(at -2.9 -0.6 270)
			(size 0.2 0.6)
			(layers "F.Cu" "F.Paste" "F.Mask")
			(roundrect_rratio 0.25)
			(net 306 "/USB Debug, DP/USBC0_SSEQ1")
			(pinfunction "SSEQ1")
			(pintype "input")
		)
		(pad "4" smd roundrect
			(at -2.9 -0.202 270)
			(size 0.2 0.6)
			(layers "F.Cu" "F.Paste" "F.Mask")
			(roundrect_rratio 0.25)
			(net 186 "/USB Debug, DP/USBSS0_RX_C_N")
			(pinfunction "SSRX_N")
			(pintype "output")
		)
		(pad "5" smd roundrect
			(at -2.9 0.2 270)
			(size 0.2 0.6)
			(layers "F.Cu" "F.Paste" "F.Mask")
			(roundrect_rratio 0.25)
			(net 193 "/USB Debug, DP/USBSS0_RX_C_P")
			(pinfunction "SSRX_P")
			(pintype "output")
		)
		(pad "6" smd roundrect
			(at -2.9 0.598 270)
			(size 0.2 0.6)
			(layers "F.Cu" "F.Paste" "F.Mask")
			(roundrect_rratio 0.25)
			(net 87 "+3V3")
			(pinfunction "VCC")
			(pintype "passive")
		)
		(pad "7" smd roundrect
			(at -2.9 0.998 270)
			(size 0.2 0.6)
			(layers "F.Cu" "F.Paste" "F.Mask")
			(roundrect_rratio 0.25)
			(net 187 "/USB Debug, DP/USBSS0_TX_C_N")
			(pinfunction "SSTX_N")
			(pintype "input")
		)
		(pad "8" smd roundrect
			(at -2.9 1.398 270)
			(size 0.2 0.6)
			(layers "F.Cu" "F.Paste" "F.Mask")
			(roundrect_rratio 0.25)
			(net 194 "/USB Debug, DP/USBSS0_TX_C_P")
			(pinfunction "SSTX_P")
			(pintype "input")
		)
		(pad "9" smd roundrect
			(at -2.202 1.898)
			(size 0.2 0.6)
			(layers "F.Cu" "F.Paste" "F.Mask")
			(roundrect_rratio 0.25)
			(net 496 "DP1_TXD0_P")
			(pinfunction "DP0_P")
			(pintype "input")
		)
		(pad "10" smd roundrect
			(at -1.801 1.898)
			(size 0.2 0.6)
			(layers "F.Cu" "F.Paste" "F.Mask")
			(roundrect_rratio 0.25)
			(net 26 "DP1_TXD0_N")
			(pinfunction "DP0_N")
			(pintype "input")
		)
		(pad "11" smd roundrect
			(at -1.401 1.898)
			(size 0.2 0.6)
			(layers "F.Cu" "F.Paste" "F.Mask")
			(roundrect_rratio 0.25)
			(net 305 "/USB Debug, DP/USBC0_SSEQ0")
			(pinfunction "SSEQ0/A0")
			(pintype "input")
		)
		(pad "12" smd roundrect
			(at -1 1.898)
			(size 0.2 0.6)
			(layers "F.Cu" "F.Paste" "F.Mask")
			(roundrect_rratio 0.25)
			(net 27 "DP1_TXD1_P")
			(pinfunction "DP1_P")
			(pintype "input")
		)
		(pad "13" smd roundrect
			(at -0.6 1.898)
			(size 0.2 0.6)
			(layers "F.Cu" "F.Paste" "F.Mask")
			(roundrect_rratio 0.25)
			(net 490 "DP1_TXD1_N")
			(pinfunction "DP1_N")
			(pintype "input")
		)
		(pad "14" smd roundrect
			(at -0.202 1.898)
			(size 0.2 0.6)
			(layers "F.Cu" "F.Paste" "F.Mask")
			(roundrect_rratio 0.25)
			(net 307 "/USB Debug, DP/USBC0_DPEQ0")
			(pinfunction "DPEQ0/A1")
			(pintype "input")
		)
		(pad "15" smd roundrect
			(at 0.2 1.898)
			(size 0.2 0.6)
			(layers "F.Cu" "F.Paste" "F.Mask")
			(roundrect_rratio 0.25)
			(net 497 "DP1_TXD2_P")
			(pinfunction "DP2_P")
			(pintype "input")
		)
		(pad "16" smd roundrect
			(at 0.598 1.898)
			(size 0.2 0.6)
			(layers "F.Cu" "F.Paste" "F.Mask")
			(roundrect_rratio 0.25)
			(net 491 "DP1_TXD2_N")
			(pinfunction "DP2_N")
			(pintype "input")
		)
		(pad "17" smd roundrect
			(at 0.998 1.898)
			(size 0.2 0.6)
			(layers "F.Cu" "F.Paste" "F.Mask")
			(roundrect_rratio 0.25)
			(net 304 "/USB Debug, DP/USBC0_I2C_EN")
			(pinfunction "I2C_EN")
			(pintype "input")
		)
		(pad "18" smd roundrect
			(at 1.398 1.898)
			(size 0.2 0.6)
			(layers "F.Cu" "F.Paste" "F.Mask")
			(roundrect_rratio 0.25)
			(net 29 "DP1_TXD3_P")
			(pinfunction "DP3_P")
			(pintype "input")
		)
		(pad "19" smd roundrect
			(at 1.8 1.898)
			(size 0.2 0.6)
			(layers "F.Cu" "F.Paste" "F.Mask")
			(roundrect_rratio 0.25)
			(net 28 "DP1_TXD3_N")
			(pinfunction "DP3_N")
			(pintype "input")
		)
		(pad "20" smd roundrect
			(at 2.2 1.898)
			(size 0.2 0.6)
			(layers "F.Cu" "F.Paste" "F.Mask")
			(roundrect_rratio 0.25)
			(net 87 "+3V3")
			(pinfunction "VCC")
			(pintype "passive")
		)
		(pad "21" smd roundrect
			(at 2.898 1.398 90)
			(size 0.2 0.6)
			(layers "F.Cu" "F.Paste" "F.Mask")
			(roundrect_rratio 0.25)
			(net 293 "/USB Debug, DP/USBC0_FLIP")
			(pinfunction "FLIP/SCL")
			(pintype "input")
		)
		(pad "22" smd roundrect
			(at 2.898 0.998 90)
			(size 0.2 0.6)
			(layers "F.Cu" "F.Paste" "F.Mask")
			(roundrect_rratio 0.25)
			(net 295 "/USB Debug, DP/USBC0_CTL0")
			(pinfunction "CTL0/SDA")
			(pintype "input")
		)
		(pad "23" smd roundrect
			(at 2.898 0.598 90)
			(size 0.2 0.6)
			(layers "F.Cu" "F.Paste" "F.Mask")
			(roundrect_rratio 0.25)
			(net 297 "/USB Debug, DP/USBC0_CTL1")
			(pinfunction "CTL1/HPDIN")
			(pintype "input")
		)
		(pad "24" smd roundrect
			(at 2.898 0.2 90)
			(size 0.2 0.6)
			(layers "F.Cu" "F.Paste" "F.Mask")
			(roundrect_rratio 0.25)
			(net 36 "DP1_AUX_P")
			(pinfunction "AUX_P")
			(pintype "bidirectional")
		)
		(pad "25" smd roundrect
			(at 2.898 -0.202 90)
			(size 0.2 0.6)
			(layers "F.Cu" "F.Paste" "F.Mask")
			(roundrect_rratio 0.25)
			(net 35 "DP1_AUX_N")
			(pinfunction "AUX_N")
			(pintype "bidirectional")
		)
		(pad "26" smd roundrect
			(at 2.898 -0.6 90)
			(size 0.2 0.6)
			(layers "F.Cu" "F.Paste" "F.Mask")
			(roundrect_rratio 0.25)
			(net 614 "/USB Debug, DP/USBC0_SBU_P")
			(pinfunction "SBU2")
			(pintype "bidirectional")
		)
		(pad "27" smd roundrect
			(at 2.898 -1 90)
			(size 0.2 0.6)
			(layers "F.Cu" "F.Paste" "F.Mask")
			(roundrect_rratio 0.25)
			(net 615 "/USB Debug, DP/USBC0_SBU_N")
			(pinfunction "SBU1")
			(pintype "bidirectional")
		)
		(pad "28" smd roundrect
			(at 2.898 -1.401 90)
			(size 0.2 0.6)
			(layers "F.Cu" "F.Paste" "F.Mask")
			(roundrect_rratio 0.25)
			(net 87 "+3V3")
			(pinfunction "VCC")
			(pintype "passive")
		)
		(pad "29" smd roundrect
			(at 2.2 -1.901 180)
			(size 0.2 0.6)
			(layers "F.Cu" "F.Paste" "F.Mask")
			(roundrect_rratio 0.25)
			(net 692 "Net-(U10-CAD_SNK{slash}RSVD1)")
			(pinfunction "CAD_SNK/RSVD1")
			(pintype "bidirectional")
		)
		(pad "30" smd roundrect
			(at 1.8 -1.901 180)
			(size 0.2 0.6)
			(layers "F.Cu" "F.Paste" "F.Mask")
			(roundrect_rratio 0.25)
			(net 154 "/USB Debug, DP/USBC0_RX1_P")
			(pinfunction "RX1_P")
			(pintype "input")
		)
		(pad "31" smd roundrect
			(at 1.398 -1.901 180)
			(size 0.2 0.6)
			(layers "F.Cu" "F.Paste" "F.Mask")
			(roundrect_rratio 0.25)
			(net 152 "/USB Debug, DP/USBC0_RX1_N")
			(pinfunction "RX1_N")
			(pintype "input")
		)
		(pad "32" smd roundrect
			(at 0.998 -1.901 180)
			(size 0.2 0.6)
			(layers "F.Cu" "F.Paste" "F.Mask")
			(roundrect_rratio 0.25)
			(net 502 "/USB Debug, DP/HPDIN")
			(pinfunction "HPDIN/RSVD2")
			(pintype "bidirectional")
		)
		(pad "33" smd roundrect
			(at 0.598 -1.901 180)
			(size 0.2 0.6)
			(layers "F.Cu" "F.Paste" "F.Mask")
			(roundrect_rratio 0.25)
			(net 257 "/USB Debug, DP/USBC0_TX1_P")
			(pinfunction "TX1_P")
			(pintype "output")
		)
		(pad "34" smd roundrect
			(at 0.2 -1.901 180)
			(size 0.2 0.6)
			(layers "F.Cu" "F.Paste" "F.Mask")
			(roundrect_rratio 0.25)
			(net 197 "/USB Debug, DP/USBC0_TX1_N")
			(pinfunction "TX1_N")
			(pintype "output")
		)
		(pad "35" smd roundrect
			(at -0.202 -1.901 180)
			(size 0.2 0.6)
			(layers "F.Cu" "F.Paste" "F.Mask")
			(roundrect_rratio 0.25)
			(net 310 "/USB Debug, DP/USBC0_EQ1")
			(pinfunction "EQ1")
			(pintype "input")
		)
		(pad "36" smd roundrect
			(at -0.6 -1.901 180)
			(size 0.2 0.6)
			(layers "F.Cu" "F.Paste" "F.Mask")
			(roundrect_rratio 0.25)
			(net 200 "/USB Debug, DP/USBC0_TX2_N")
			(pinfunction "TX2_N")
			(pintype "output")
		)
		(pad "37" smd roundrect
			(at -1 -1.901 180)
			(size 0.2 0.6)
			(layers "F.Cu" "F.Paste" "F.Mask")
			(roundrect_rratio 0.25)
			(net 259 "/USB Debug, DP/USBC0_TX2_P")
			(pinfunction "TX2_P")
			(pintype "output")
		)
		(pad "38" smd roundrect
			(at -1.401 -1.901 180)
			(size 0.2 0.6)
			(layers "F.Cu" "F.Paste" "F.Mask")
			(roundrect_rratio 0.25)
			(net 309 "/USB Debug, DP/USBC0_EQ0")
			(pinfunction "EQ0")
			(pintype "input")
		)
		(pad "39" smd roundrect
			(at -1.801 -1.901 180)
			(size 0.2 0.6)
			(layers "F.Cu" "F.Paste" "F.Mask")
			(roundrect_rratio 0.25)
			(net 125 "/USB Debug, DP/USBC0_RX2_N")
			(pinfunction "RX2_N")
			(pintype "input")
		)
		(pad "40" smd roundrect
			(at -2.202 -1.901 180)
			(size 0.2 0.6)
			(layers "F.Cu" "F.Paste" "F.Mask")
			(roundrect_rratio 0.25)
			(net 151 "/USB Debug, DP/USBC0_RX2_P")
			(pinfunction "RX2_P")
			(pintype "input")
		)
		(pad "41" smd roundrect
			(at -1.5 -0.652)
			(size 1 0.8)
			(layers "F.Cu" "F.Paste" "F.Mask")
			(roundrect_rratio 0.05)
			(net 1 "GND")
			(pinfunction "GND")
			(pintype "power_in")
		)
		(pad "41" smd roundrect
			(at -1.5 0.748)
			(size 1 0.8)
			(layers "F.Cu" "F.Paste" "F.Mask")
			(roundrect_rratio 0.05)
			(net 1 "GND")
			(pinfunction "GND")
			(pintype "power_in")
		)
		(pad "41" smd roundrect
			(at 0 0)
			(size 4.7 2.7)
			(layers "F.Cu" "F.Mask")
			(roundrect_rratio 0.01851851852)
			(net 1 "GND")
			(pinfunction "GND")
			(pintype "power_in")
		)
		(pad "41" smd roundrect
			(at 0.05 -0.652)
			(size 1 0.8)
			(layers "F.Cu" "F.Paste" "F.Mask")
			(roundrect_rratio 0.05)
			(net 1 "GND")
			(pinfunction "GND")
			(pintype "power_in")
		)
		(pad "41" smd roundrect
			(at 0.05 0.748)
			(size 1 0.8)
			(layers "F.Cu" "F.Paste" "F.Mask")
			(roundrect_rratio 0.05)
			(net 1 "GND")
			(pinfunction "GND")
			(pintype "power_in")
		)
		(pad "41" smd roundrect
			(at 1.499 -0.652)
			(size 1 0.8)
			(layers "F.Cu" "F.Paste" "F.Mask")
			(roundrect_rratio 0.05)
			(net 1 "GND")
			(pinfunction "GND")
			(pintype "power_in")
		)
		(pad "41" smd roundrect
			(at 1.499 0.748)
			(size 1 0.8)
			(layers "F.Cu" "F.Paste" "F.Mask")
			(roundrect_rratio 0.05)
			(net 1 "GND")
			(pinfunction "GND")
			(pintype "power_in")
		)
	)
)
